# TIMECARD (Time Appliance Project (Time Card)) — schematic netlist excerpt (pin names and nets, part order shuffled) for the footprints in the layout excerpt that follows; sources: Cadence DE-HDL packaged netlist, KiCad conversion of R4006-B0001-02_R01.brd

R155  RESISTOR  4.7KOHM 1%  pkg SMC_0402R_H016  page 16 : \1\ = SG ; \2\ = PCA9546_RST_N
C156  CAPACITOR  0.1UF 10V 10%  pkg SMC_0402R_H022  page 14 : \1\ = XP1R0V_FPGA_VCCINT ; \2\ = SG

(kicad_pcb
	(version 20260206)
	(generator "pcbnew")
	(generator_version "10.0")
	(general
		(thickness 1.6)
		(legacy_teardrops no)
	)
	(paper "A4")
	(title_block
		(title "timecard-production-celestica-r4006 — R4006-B0001-02_R01.brd")
		(comment 1 "Time Appliance Project (Time Card) / footprints 1049-1050 of 1113")
	)
	(layers
		(0 "F.Cu" signal "TOP")
		(4 "In1.Cu" signal "L02_GND1")
		(6 "In2.Cu" signal "L03_SIG1")
		(8 "In3.Cu" signal "L04_GND2")
		(10 "In4.Cu" signal "L05_VCC1")
		(12 "In5.Cu" signal "L06_VCC2")
		(14 "In6.Cu" signal "L07_GND3")
		(16 "In7.Cu" signal "L08_SIG2")
		(18 "In8.Cu" signal "L09_GND4")
		(2 "B.Cu" signal "BOTTOM")
		(9 "F.Adhes" user "F.Adhesive")
		(11 "B.Adhes" user "B.Adhesive")
		(13 "F.Paste" user "Package Geometry/Pastemask Top")
		(15 "B.Paste" user "Package Geometry/Pastemask Bottom")
		(5 "F.SilkS" user "Ref Des/Silkscreen Top")
		(7 "B.SilkS" user "Ref Des/Silkscreen Bottom")
		(1 "F.Mask" user "Board Geometry/Soldermask Top")
		(3 "B.Mask" user "Board Geometry/Soldermask Bottom")
		(17 "Dwgs.User" user "User.Drawings")
		(19 "Cmts.User" user "User.Comments")
		(21 "Eco1.User" user "User.Eco1")
		(23 "Eco2.User" user "User.Eco2")
		(25 "Edge.Cuts" user "Board Geometry/Outline")
		(27 "Margin" user)
		(31 "F.CrtYd" user "Package Geometry/Place Bound Top")
		(29 "B.CrtYd" user "Package Geometry/Place Bound Bottom")
		(35 "F.Fab" user "Ref Des/Assembly Top")
		(33 "B.Fab" user "Ref Des/Assembly Bottom")
	)
	(footprint ""
		(layer "B.Cu")
		(at 83.2358 -87.122 180)
		(property "Reference" "R155"
			(at 0.6858 5.42163 0)
			(unlocked yes)
			(layer "B.SilkS")
			(effects
				(font
					(size 0.7874 0.5842)
					(thickness 0.1524)
				)
				(justify mirror)
			)
		)
		(property "Value" "VAL*"
			(at -0.02032 2.13233 180)
			(unlocked yes)
			(layer "B.Fab")
			(hide yes)
			(effects
				(font
					(size 0.7874 0.5842)
					(thickness 0.1524)
				)
				(justify mirror)
			)
		)
		(property "Tolerance" "TOL*"
			(at -0.044704 3.05435 180)
			(unlocked yes)
			(layer "Cmts.User")
			(hide yes)
			(effects
				(font
					(size 0.7874 0.5842)
					(thickness 0.1524)
				)
				(justify mirror)
			)
		)
		(property "User Part Number" "PARTNUM*"
			(at -0.02032 4.024884 180)
			(unlocked yes)
			(layer "Cmts.User")
			(hide yes)
			(effects
				(font
					(size 0.7874 0.5842)
					(thickness 0.1524)
				)
				(justify mirror)
			)
		)
		(property "Device Type" "RESISTOR-G155-14701-01,4.7KOHMA"
			(at -0.008382 1.210564 180)
			(unlocked yes)
			(layer "B.Fab")
			(hide yes)
			(effects
				(font
					(size 0.7874 0.5842)
					(thickness 0.1524)
				)
				(justify mirror)
			)
		)
		(duplicate_pad_numbers_are_jumpers no)
		(fp_line
			(start 1.143 0.5588)
			(end -1.143 0.5588)
			(stroke
				(width 0.1)
				(type default)
			)
			(layer "B.SilkS")
		)
		(fp_line
			(start 1.143 -0.5588)
			(end 1.143 0.5588)
			(stroke
				(width 0.1)
				(type default)
			)
			(layer "B.SilkS")
		)
		(fp_line
			(start -1.143 0.5588)
			(end -1.143 -0.5588)
			(stroke
				(width 0.1)
				(type default)
			)
			(layer "B.SilkS")
		)
		(fp_line
			(start -1.143 -0.5588)
			(end 1.143 -0.5588)
			(stroke
				(width 0.1)
				(type default)
			)
			(layer "B.SilkS")
		)
		(fp_rect
			(start -1.143 0.5588)
			(end 1.143 -0.5588)
			(stroke
				(width 0)
				(type default)
			)
			(fill no)
			(layer "B.CrtYd")
		)
		(fp_line
			(start 0.508 0.3048)
			(end -0.508 0.3048)
			(stroke
				(width 0.1)
				(type default)
			)
			(layer "B.Fab")
		)
		(fp_line
			(start 0.508 -0.3048)
			(end 0.508 0.3048)
			(stroke
				(width 0.1)
				(type default)
			)
			(layer "B.Fab")
		)
		(fp_line
			(start -0.508 0.3048)
			(end -0.508 -0.3048)
			(stroke
				(width 0.1)
				(type default)
			)
			(layer "B.Fab")
		)
		(fp_line
			(start -0.508 -0.3048)
			(end 0.508 -0.3048)
			(stroke
				(width 0.1)
				(type default)
			)
			(layer "B.Fab")
		)
		(pad "1" smd rect
			(at 0.5334 0)
			(size 0.7112 0.6096)
			(layers "B.Cu" "B.Mask" "B.Paste")
			(net "SG")
		)
		(pad "2" smd rect
			(at -0.5334 0)
			(size 0.7112 0.6096)
			(layers "B.Cu" "B.Mask" "B.Paste")
			(net "PCA9546_RST_N")
		)
		(zone
			(layer "B.Cu")
			(hatch none 0.5)
			(connect_pads
				(clearance 0)
			)
			(min_thickness 0.25)
			(keepout
				(tracks allowed)
				(vias not_allowed)
				(pads allowed)
				(copperpour not_allowed)
				(footprints allowed)
			)
			(placement
				(enabled no)
				(sheetname "")
			)
			(fill
				(thermal_gap 0.5)
				(thermal_bridge_width 0.5)
				(island_removal_mode 0)
			)
			(polygon
				(pts
					(xy 83.312 -87.4268) (xy 83.1596 -87.4268) (xy 83.1596 -86.8172) (xy 83.312 -86.8172)
				)
			)
		)
	)
	(footprint ""
		(layer "B.Cu")
		(at 105.847134 -42.323258 -90)
		(property "Reference" "C156"
			(at 1.015238 41.383204 270)
			(unlocked yes)
			(layer "B.SilkS")
			(effects
				(font
					(size 0.635 0.4064)
					(thickness 0.1524)
				)
				(justify mirror)
			)
		)
		(property "Value" "VAL*"
			(at 0 3.718306 270)
			(unlocked yes)
			(layer "B.Fab")
			(hide yes)
			(effects
				(font
					(size 0.7874 0.5842)
					(thickness 0.127)
				)
				(justify mirror)
			)
		)
		(property "Device Type" "CAPACITOR-G105-0B104-CK,0.1UF,A"
			(at 0 1.432306 270)
			(unlocked yes)
			(layer "B.Fab")
			(hide yes)
			(effects
				(font
					(size 0.7874 0.5842)
					(thickness 0.127)
				)
				(justify mirror)
			)
		)
		(property "User Part Number" "PARTNUM*"
			(at 0 2.575306 270)
			(unlocked yes)
			(layer "Cmts.User")
			(hide yes)
			(effects
				(font
					(size 0.7874 0.5842)
					(thickness 0.127)
				)
				(justify mirror)
			)
		)
		(property "Tolerance" "TOL*"
			(at 0 4.861306 270)
			(unlocked yes)
			(layer "Cmts.User")
			(hide yes)
			(effects
				(font
					(size 0.7874 0.5842)
					(thickness 0.127)
				)
				(justify mirror)
			)
		)
		(duplicate_pad_numbers_are_jumpers no)
		(fp_line
			(start -0.970026 0.4699)
			(end 0.970026 0.4699)
			(stroke
				(width 0.1)
				(type default)
			)
			(layer "B.SilkS")
		)
		(fp_line
			(start 0.970026 0.4699)
			(end 0.970026 -0.4699)
			(stroke
				(width 0.1)
				(type default)
			)
			(layer "B.SilkS")
		)
		(fp_line
			(start -0.970026 -0.4699)
			(end -0.970026 0.4699)
			(stroke
				(width 0.1)
				(type default)
			)
			(layer "B.SilkS")
		)
		(fp_line
			(start 0.970026 -0.4699)
			(end -0.970026 -0.4699)
			(stroke
				(width 0.1)
				(type default)
			)
			(layer "B.SilkS")
		)
		(fp_poly
			(pts
				(xy 0.970026 0.4699) (xy -0.970026 0.4699) (xy -0.970026 -0.4699) (xy 0.970026 -0.4699)
			)
			(stroke
				(width 0)
				(type default)
			)
			(fill no)
			(layer "B.CrtYd")
		)
		(fp_line
			(start -0.508 0.3048)
			(end 0.508 0.3048)
			(stroke
				(width 0.1)
				(type default)
			)
			(layer "B.Fab")
		)
		(fp_line
			(start 0.508 0.3048)
			(end 0.508 -0.3048)
			(stroke
				(width 0.1)
				(type default)
			)
			(layer "B.Fab")
		)
		(fp_line
			(start -0.508 -0.3048)
			(end -0.508 0.3048)
			(stroke
				(width 0.1)
				(type default)
			)
			(layer "B.Fab")
		)
		(fp_line
			(start 0.508 -0.3048)
			(end -0.508 -0.3048)
			(stroke
				(width 0.1)
				(type default)
			)
			(layer "B.Fab")
		)
		(pad "1" smd circle
			(at 0.500126 0 90)
			(size 0.635 0.635)
			(layers "B.Cu" "B.Mask" "B.Paste")
			(net "XP1R0V_FPGA_VCCINT")
		)
		(pad "2" smd circle
			(at -0.500126 0 90)
			(size 0.635 0.635)
			(layers "B.Cu" "B.Mask" "B.Paste")
			(net "SG")
		)
	)
)
